#ISCELL
  mstr_misc dns *
  *
#ISCELL
  pure_quanta quanta_title_block_c *
  *
#CELL
  pure_quanta m24128bwmn6tp *
  page231_i35
#ISCELL
  standard offpage *
  page231_i40
#ISCELL
  standard offpage *
  page231_i41
#CELL
  pure_quanta q_res *
  page231_i45
#CELL
  pure_quanta q_res *
  page231_i47
#ISCELL
  logical_power universal_gnd *
  page231_i49
#CELL
  pure_quanta q_res *
  page231_i50
#ISCELL
  logical_power universal_gnd *
  page231_i51
#CELL
  pure_quanta q_res *
  page231_i52
#ISCELL
  logical_power universal_gnd *
  page231_i53
#ISCELL
  logical_power universal_power *
  page231_i54
#CELL
  pure_quanta q_cap *
  page231_i55
#ISCELL
  logical_power universal_gnd *
  page231_i56
#CELL
  pure_quanta q_res *
  page231_i57
#ISCELL
  logical_power universal_gnd *
  page231_i58
#ISCELL
  logical_power universal_gnd *
  page231_i59
#ISCELL
  logical_power universal_power *
  page231_i60
#CELL
  pure_quanta q_res *
  page231_i61
#CELL
  pure_quanta q_res *
  page231_i62
#CELL
  pure_quanta q_res *
  page231_i93
#CELL
  pure_quanta q_res *
  page231_i95
#ISCELL
  logical_power universal_power *
  page231_i96
